FILE_TYPE = MULTI_PHYS_TABLE;

PART 'MEC_MTH8'
CLASS=IO

{========================================================================================}
:JEDEC_TYPE                    = JEDEC_TYPE                    ;
{========================================================================================}
 'MTH_8_106C096N'              = 'MTH_8_106C096N'             
 'MTH130C276N_V8'              = 'MTH130C276N_V8'             
 'MTH126C394N_V8'              = 'MTH126C394N_V8'             
 'MTH126CT315B236N_V8'         = 'MTH126CT315B236N_V8'        
 'MTH165C276N_V8'              = 'MTH165C276N_V8'             
 'MTH177C315N_V8'              = 'MTH177C315N_V8'             
 'MTH118C295N_V8'              = 'MTH118C295N_V8'             
 'MTH138C295N_V8'              = 'MTH138C295N_V8'             
 'MTH118X157OB295N_V8'         = 'MTH118X157OB295N_V8'        
 'MTH118C335N_V8'              = 'MTH118C335N_V8'             
 'MTH138C335N_V8'              = 'MTH138C335N_V8'             
 'MTH118X157OB335N_V8'         = 'MTH118X157OB335N_V8'        
 'MTH118C335N_V8_CST'          = 'MTH118C335N_V8_CST'         
 'MTH138C335N_V8_CST'          = 'MTH138C335N_V8_CST'         
 'MTH118X157OB335N_V8_CST'     = 'MTH118X157OB335N_V8_CST'    
 'MTH138C394N_V8'              = 'MTH138C394N_V8'             
 'MTH130C217N_V8'              = 'MTH130C217N_V8'             
 'MTH138C394N_V8_V1'           = 'MTH138C394N_V8_V1'          
 'MTH138C394N_V8_V2'           = 'MTH138C394N_V8_V2'          
 'MTH169C335N_V8'              = 'MTH169C335N_V8'             
 'MTH118C354N_V8'              = 'MTH118C354N_V8'             
 'MTH252C394N_V8'              = 'MTH252C394N_V8'             
 'MTH157C394N_V8'              = 'MTH157C394N_V8'             
 'MTH124C256N_V8'              = 'MTH124C256N_V8'             
 'MTH169C315N_V8'              = 'MTH169C315N_V8'             
 'MTH138C315N_V8'              = 'MTH138C315N_V8'             
 'MTH130C394N_V8'              = 'MTH130C394N_V8'             
 'MTH130C354N_V8'              = 'MTH130C354N_V8'             
 'MTH165C354N_V8'              = 'MTH165C354N_V8'             
 'MTH142C354N_V8'              = 'MTH142C354N_V8'             
 'MTH138C276N_V8'              = 'MTH138C276N_V8'             
 'MTH169C276N_V8'              = 'MTH169C276N_V8'             
 'MTH118C276N_V8'              = 'MTH118C276N_V8'             
 'MTH134C315N_V8'              = 'MTH134C315N_V8'             
 'MTH130C315N_V8'              = 'MTH130C315N_V8'             
 'MTH165C315N_V8'              = 'MTH165C315N_V8'             
 'MTH197C315N_V8'              = 'MTH197C315N_V8'             
 'MTH138C354N_V8'              = 'MTH138C354N_V8'             
 'MTH138C244N_V8'              = 'MTH138C244N_V8'             
 'MTH205C355N_V8'              = 'MTH205C355N_V8'             
 'MTH161C354N_V8'              = 'MTH161C354N_V8'             
 'MTH201C315N_V8'              = 'MTH201C315N_V8'             
 'MTH126C276N_V8'              = 'MTH126C276N_V8'             
 'MTH087C197N_V8'              = 'MTH087C197N_V8'             
 'MTH138CT394X329B354N_V8'     = 'MTH138CT394X329B354N_V8'    
 'MTH157X138OB335N_V8'         = 'MTH157X138OB335N_V8'        
 'MTH252C472N_V8'              = 'MTH252C472N_V8'             
 'MTH201C551N_V8'              = 'MTH201C551N_V8'             
 'MTH166C256N_V8'              = 'MTH166C256N_V8'             
 'MTH098C177N_V8'              = 'MTH098C177N_V8'             
 'MTH173CT315OB650X315N_V8'    = 'MTH173CT315OB650X315N_V8'   
 'MTH138CT315OB650X315N_V8'    = 'MTH138CT315OB650X315N_V8'   
 'MTH126C315N_V8'              = 'MTH126C315N_V8'             
 'MTH130C236N_V8'              = 'MTH130C236N_V8'             
 'MTH236C394N_V8'              = 'MTH236C394N_V8'             
 'MTH177C394N_V8'              = 'MTH177C394N_V8'             
 'MTH118C315N_V8'              = 'MTH118C315N_V8'             
 'MTH166CT394B315N_V8'         = 'MTH166CT394B315N_V8'        
 'MTH165X205OB354N_V8'         = 'MTH165X205OB354N_V8'        
 'MTH228C472N_V8'              = 'MTH228C472N_V8'             
 'MTH173C315N_V8'              = 'MTH173C315N_V8'             
 'MTH189C315N_V8'              = 'MTH189C315N_V8'             
 'MTH518X236OB650X315N_NP2_V8' = 'MTH518X236OB650X315N_NP2_V8'
 'MTH193X173OB315N_V8'         = 'MTH193X173OB315N_V8'        
 'MTH138CT276B276X531N_V8'     = 'MTH138CT276B276X531N_V8'    
 'MTH134CT315OB472X315N_V8'    = 'MTH134CT315OB472X315N_V8'   
 'MTH173CT315OB472X315N_V8'    = 'MTH173CT315OB472X315N_V8'   
 'MTH134CT315OB709X315N_V8'    = 'MTH134CT315OB709X315N_V8'   
 'MTH134C276N_V8'              = 'MTH134C276N_V8'             
 'MTH157C315N_V8'              = 'MTH157C315N_V8'             
 'MTH110C236N_V8'              = 'MTH110C236N_V8'             
 'MTH125C236N_V8'              = 'MTH125C236N_V8'             
 'MTH150C236N_V8'              = 'MTH150C236N_V8'             
 'MTH217C315N_V8'              = 'MTH217C315N_V8'             
 'MTH140C256N_V8'              = 'MTH140C256N_V8'             
 'MTH106C236N_V8'              = 'MTH106C236N_V8'             
 'MTH134C236N_V8'              = 'MTH134C236N_V8'             
 'MTH185X165OB315N_V8'         = 'MTH185X165OB315N_V8'        
 'MTH110C315N_V8'              = 'MTH110C315N_V8'             
 'MTH166C315N_V8'              = 'MTH166C315N_V8'             
 'MTH256X660OB315X788N_NP2_V8' = 'MTH256X660OB315X788N_NP2_V8'
 'MTH181C315N_V8'              = 'MTH181C315N_V8'             
 'MTH157C441N_V8'              = 'MTH157C441N_V8'             
 'MTH213X173OB315N_V8'         = 'MTH213X173OB315N_V8'        
 'MTH157C315N_V8_CST'          = 'MTH157C315N_V8_CST'         
 'MTH125CT315SB500X409N_V8'    = 'MTH125CT315SB500X409N_V8'   
 'MTH125CT315SB591X364N_V8'    = 'MTH125CT315SB591X364N_V8'   
 'MTH138CT315OB275X490N'       = 'MTH138CT315OB275X490N'      
 'MTH165CT315OB275X490N'       = 'MTH165CT315OB275X490N'      
 'MTH457X236OB551X315N_NP2_V8' = 'MTH457X236OB551X315N_NP2_V8'
 'MTH165X185OB315N_V8'         = 'MTH165X185OB315N_V8'        
 'MTH213X173OB394N_V8'         = 'MTH213X173OB394N_V8'        
 'MTH118C236N_V8'              = 'MTH118C236N_V8'        
 'MTH165C236N_V8'              = 'MTH165C236N_V8'        
 'MTH138C236N_V8'              = 'MTH138C236N_V8'        
 'MTH134C472N_V8'              = 'MTH134C472N_V8' 
 'MTH185C315N_V8'              = 'MTH185C315N_V8' 
 'MTH177C472N_V8'              = 'MTH177C472N_V8' 
 'MTH150C315N_V8'              = 'MTH150C315N_V8' 
 'MTH134CT315CB124N_V8'        = 'MTH134CT315CB124N_V8' 
 'MTH228CT394CB218N_V8'        = 'MTH228CT394CB218N_V8' 
 'MTH205X165C354X315N_V8'      = 'MTH205X165C354X315N_V8' 
 'MTH213CT394OB728X394N_V8'    = 'MTH213CT394OB728X394N_V8' 

END_PART

END.

